(kicad_pcb
	(version 20260206)
	(generator "pcbnew")
	(generator_version "10.0")
	(general
		(thickness 1.6)
		(legacy_teardrops no)
	)
	(paper "A4")
	(title_block
		(title "panther-plus-userver — 13130-1b_20150205.brd")
		(comment 1 "Honey Badger (Wiwynn) / footprints 705-712 of 1509")
	)
	(layers
		(0 "F.Cu" signal "TOP")
		(4 "In1.Cu" signal "L2")
		(6 "In2.Cu" signal "L3")
		(8 "In3.Cu" signal "L4")
		(10 "In4.Cu" signal "L5")
		(12 "In5.Cu" signal "L6")
		(14 "In6.Cu" signal "L7")
		(16 "In7.Cu" signal "L8")
		(18 "In8.Cu" signal "L9")
		(20 "In9.Cu" signal "L10")
		(22 "In10.Cu" signal "L11")
		(2 "B.Cu" signal "BOTTOM")
		(9 "F.Adhes" user "F.Adhesive")
		(11 "B.Adhes" user "B.Adhesive")
		(13 "F.Paste" user "Package Geometry/Pastemask Top")
		(15 "B.Paste" user "Package Geometry/Pastemask Bottom")
		(5 "F.SilkS" user "Ref Des/Silkscreen Top")
		(7 "B.SilkS" user "Ref Des/Silkscreen Bottom")
		(1 "F.Mask" user "Board Geometry/Soldermask Top")
		(3 "B.Mask" user "Board Geometry/Soldermask Bottom")
		(17 "Dwgs.User" user "User.Drawings")
		(19 "Cmts.User" user "User.Comments")
		(21 "Eco1.User" user "User.Eco1")
		(23 "Eco2.User" user "User.Eco2")
		(25 "Edge.Cuts" user "Board Geometry/Outline")
		(27 "Margin" user)
		(31 "F.CrtYd" user "Package Geometry/Place Bound Top")
		(29 "B.CrtYd" user "Package Geometry/Place Bound Bottom")
		(35 "F.Fab" user "Ref Des/Assembly Top")
		(33 "B.Fab" user "Ref Des/Assembly Bottom")
	)
	(footprint ""
		(layer "F.Cu")
		(at 167.894 -23.114 -90)
		(property "Reference" "PR146"
			(at 0 0 270)
			(layer "F.SilkS")
			(hide yes)
			(effects
				(font
					(size 1.27 1.27)
				)
			)
		)
		(property "Value" "0R3J-6-GP"
			(at -0.0254 -2.5146 270)
			(unlocked yes)
			(layer "F.Fab")
			(hide yes)
			(effects
				(font
					(size 1.016 1.016)
					(thickness 0.1524)
				)
			)
		)
		(property "Device Type" "R603H22"
			(at -0.0254 -4.0386 270)
			(unlocked yes)
			(layer "F.Fab")
			(hide yes)
			(effects
				(font
					(size 1.016 1.016)
					(thickness 0.1524)
				)
			)
		)
		(duplicate_pad_numbers_are_jumpers no)
		(fp_line
			(start -0.2032 0)
			(end -0.4191 0)
			(stroke
				(width 0.2032)
				(type default)
			)
			(layer "F.SilkS")
		)
		(fp_line
			(start 0.4318 0)
			(end 0.2032 0)
			(stroke
				(width 0.2032)
				(type default)
			)
			(layer "F.SilkS")
		)
		(fp_rect
			(start -0.635 1.1811)
			(end 0.635 -1.1811)
			(stroke
				(width 0)
				(type default)
			)
			(fill no)
			(layer "F.CrtYd")
		)
		(fp_rect
			(start -0.635 1.1811)
			(end 0.635 -1.1811)
			(stroke
				(width 0)
				(type default)
			)
			(fill no)
			(layer "F.Fab")
		)
		(pad "1" smd custom
			(at 0 -0.6604 270)
			(size 0.19685 0.19685)
			(layers "F.Cu" "F.Mask" "F.Paste")
			(net "P1V8_STBY_LDO_IN2")
			(options
				(clearance outline)
				(anchor circle)
			)
			(primitives
				(gr_poly
					(pts
						(arc
							(start 0.508 -0.2921)
							(mid 0.478242 -0.363942)
							(end 0.4064 -0.3937)
						)
						(arc
							(start -0.4064 -0.3937)
							(mid -0.478242 -0.363942)
							(end -0.508 -0.2921)
						)
						(arc
							(start -0.508 0.2921)
							(mid -0.478242 0.363942)
							(end -0.4064 0.3937)
						)
						(arc
							(start 0.4064 0.3937)
							(mid 0.478242 0.363942)
							(end 0.508 0.2921)
						)
					)
					(width 0)
					(fill yes)
				)
			)
		)
		(pad "2" smd custom
			(at 0 0.6604 270)
			(size 0.19685 0.19685)
			(layers "F.Cu" "F.Mask" "F.Paste")
			(net "P3V3_STBY")
			(options
				(clearance outline)
				(anchor circle)
			)
			(primitives
				(gr_poly
					(pts
						(arc
							(start 0.508 -0.2921)
							(mid 0.478242 -0.363942)
							(end 0.4064 -0.3937)
						)
						(arc
							(start -0.4064 -0.3937)
							(mid -0.478242 -0.363942)
							(end -0.508 -0.2921)
						)
						(arc
							(start -0.508 0.2921)
							(mid -0.478242 0.363942)
							(end -0.4064 0.3937)
						)
						(arc
							(start 0.4064 0.3937)
							(mid 0.478242 0.363942)
							(end 0.508 0.2921)
						)
					)
					(width 0)
					(fill yes)
				)
			)
		)
	)
	(footprint ""
		(layer "F.Cu")
		(at 30.099 -33.02)
		(property "Reference" "C122"
			(at 0 0 0)
			(layer "F.SilkS")
			(hide yes)
			(effects
				(font
					(size 1.27 1.27)
				)
			)
		)
		(property "Value" "SCD1U16V2KX-3GP"
			(at 1.1811 -2.7051 0)
			(unlocked yes)
			(layer "F.Fab")
			(hide yes)
			(effects
				(font
					(size 1.016 1.016)
					(thickness 0.1524)
				)
			)
		)
		(property "Device Type" "C402H22"
			(at 1.1811 -4.2291 0)
			(unlocked yes)
			(layer "F.Fab")
			(hide yes)
			(effects
				(font
					(size 1.016 1.016)
					(thickness 0.1524)
				)
			)
		)
		(duplicate_pad_numbers_are_jumpers no)
		(fp_rect
			(start -0.381 0.7366)
			(end 0.381 -0.7366)
			(stroke
				(width 0)
				(type default)
			)
			(fill no)
			(layer "F.CrtYd")
		)
		(fp_rect
			(start -0.381 0.7366)
			(end 0.381 -0.7366)
			(stroke
				(width 0)
				(type default)
			)
			(fill no)
			(layer "F.Fab")
		)
		(pad "1" smd custom
			(at 0 -0.4572)
			(size 0.1143 0.1143)
			(layers "F.Cu" "F.Mask" "F.Paste")
			(net "GND")
			(options
				(clearance outline)
				(anchor circle)
			)
			(primitives
				(gr_poly
					(pts
						(arc
							(start -0.254 -0.1778)
							(mid -0.239121 -0.213721)
							(end -0.2032 -0.2286)
						)
						(arc
							(start 0.2032 -0.2286)
							(mid 0.239121 -0.213721)
							(end 0.254 -0.1778)
						)
						(arc
							(start 0.254 0.1778)
							(mid 0.239121 0.213721)
							(end 0.2032 0.2286)
						)
						(arc
							(start -0.2032 0.2286)
							(mid -0.239121 0.213721)
							(end -0.254 0.1778)
						)
					)
					(width 0)
					(fill yes)
				)
			)
		)
		(pad "2" smd custom
			(at 0 0.4572)
			(size 0.1143 0.1143)
			(layers "F.Cu" "F.Mask" "F.Paste")
			(net "XDP_CPU_RESET#")
			(options
				(clearance outline)
				(anchor circle)
			)
			(primitives
				(gr_poly
					(pts
						(arc
							(start -0.254 -0.1778)
							(mid -0.239121 -0.213721)
							(end -0.2032 -0.2286)
						)
						(arc
							(start 0.2032 -0.2286)
							(mid 0.239121 -0.213721)
							(end 0.254 -0.1778)
						)
						(arc
							(start 0.254 0.1778)
							(mid 0.239121 0.213721)
							(end 0.2032 0.2286)
						)
						(arc
							(start -0.2032 0.2286)
							(mid -0.239121 0.213721)
							(end -0.254 0.1778)
						)
					)
					(width 0)
					(fill yes)
				)
			)
		)
	)
	(footprint ""
		(layer "F.Cu")
		(at 15.8496 -59.1312 90)
		(property "Reference" "R20"
			(at 0 0 90)
			(layer "F.SilkS")
			(hide yes)
			(effects
				(font
					(size 1.27 1.27)
				)
			)
		)
		(property "Value" "150R2J-L1-GP-U"
			(at 1.7907 -1.1176 90)
			(unlocked yes)
			(layer "F.Fab")
			(hide yes)
			(effects
				(font
					(size 1.016 1.016)
					(thickness 0.1524)
				)
			)
		)
		(property "Device Type" "R402H16"
			(at 1.7907 -2.6416 90)
			(unlocked yes)
			(layer "F.Fab")
			(hide yes)
			(effects
				(font
					(size 1.016 1.016)
					(thickness 0.1524)
				)
			)
		)
		(duplicate_pad_numbers_are_jumpers no)
		(fp_rect
			(start -0.381 0.8382)
			(end 0.381 -0.8382)
			(stroke
				(width 0)
				(type default)
			)
			(fill no)
			(layer "F.CrtYd")
		)
		(fp_rect
			(start -0.381 0.8382)
			(end 0.381 -0.8382)
			(stroke
				(width 0)
				(type default)
			)
			(fill no)
			(layer "F.Fab")
		)
		(pad "1" smd custom
			(at 0 -0.4318 90)
			(size 0.127 0.127)
			(layers "F.Cu" "F.Mask" "F.Paste")
			(net "SVID_CPU_CLK")
			(options
				(clearance outline)
				(anchor circle)
			)
			(primitives
				(gr_poly
					(pts
						(arc
							(start -0.2032 -0.2794)
							(mid -0.239121 -0.264521)
							(end -0.254 -0.2286)
						)
						(arc
							(start -0.254 0.2286)
							(mid -0.239121 0.264521)
							(end -0.2032 0.2794)
						)
						(arc
							(start 0.2032 0.2794)
							(mid 0.239121 0.264521)
							(end 0.254 0.2286)
						)
						(arc
							(start 0.254 -0.2286)
							(mid 0.239121 -0.264521)
							(end 0.2032 -0.2794)
						)
					)
					(width 0)
					(fill yes)
				)
			)
		)
		(pad "2" smd custom
			(at 0 0.4318 90)
			(size 0.127 0.127)
			(layers "F.Cu" "F.Mask" "F.Paste")
			(net "VR_95831_SCLK")
			(options
				(clearance outline)
				(anchor circle)
			)
			(primitives
				(gr_poly
					(pts
						(arc
							(start -0.2032 -0.2794)
							(mid -0.239121 -0.264521)
							(end -0.254 -0.2286)
						)
						(arc
							(start -0.254 0.2286)
							(mid -0.239121 0.264521)
							(end -0.2032 0.2794)
						)
						(arc
							(start 0.2032 0.2794)
							(mid 0.239121 0.264521)
							(end 0.254 0.2286)
						)
						(arc
							(start 0.254 -0.2286)
							(mid 0.239121 -0.264521)
							(end 0.2032 -0.2794)
						)
					)
					(width 0)
					(fill yes)
				)
			)
		)
	)
	(footprint ""
		(layer "F.Cu")
		(at 77.978 -12.827 -90)
		(property "Reference" "R423"
			(at 0 0 270)
			(layer "F.SilkS")
			(hide yes)
			(effects
				(font
					(size 1.27 1.27)
				)
			)
		)
		(property "Value" "0R2J-2-GP"
			(at 1.7907 -1.1176 270)
			(unlocked yes)
			(layer "F.Fab")
			(hide yes)
			(effects
				(font
					(size 1.016 1.016)
					(thickness 0.1524)
				)
			)
		)
		(property "Device Type" "R402H16"
			(at 1.7907 -2.6416 270)
			(unlocked yes)
			(layer "F.Fab")
			(hide yes)
			(effects
				(font
					(size 1.016 1.016)
					(thickness 0.1524)
				)
			)
		)
		(duplicate_pad_numbers_are_jumpers no)
		(fp_rect
			(start -0.381 0.8382)
			(end 0.381 -0.8382)
			(stroke
				(width 0)
				(type default)
			)
			(fill no)
			(layer "F.CrtYd")
		)
		(fp_rect
			(start -0.381 0.8382)
			(end 0.381 -0.8382)
			(stroke
				(width 0)
				(type default)
			)
			(fill no)
			(layer "F.Fab")
		)
		(pad "1" smd custom
			(at 0 -0.4318 270)
			(size 0.127 0.127)
			(layers "F.Cu" "F.Mask" "F.Paste")
			(net "BMC_I2C_ALERT#")
			(options
				(clearance outline)
				(anchor circle)
			)
			(primitives
				(gr_poly
					(pts
						(arc
							(start -0.2032 -0.2794)
							(mid -0.239121 -0.264521)
							(end -0.254 -0.2286)
						)
						(arc
							(start -0.254 0.2286)
							(mid -0.239121 0.264521)
							(end -0.2032 0.2794)
						)
						(arc
							(start 0.2032 0.2794)
							(mid 0.239121 0.264521)
							(end 0.254 0.2286)
						)
						(arc
							(start 0.254 -0.2286)
							(mid 0.239121 -0.264521)
							(end 0.2032 -0.2794)
						)
					)
					(width 0)
					(fill yes)
				)
			)
		)
		(pad "2" smd custom
			(at 0 0.4318 270)
			(size 0.127 0.127)
			(layers "F.Cu" "F.Mask" "F.Paste")
			(net "PCIE_GF_I2C_ALERT#")
			(options
				(clearance outline)
				(anchor circle)
			)
			(primitives
				(gr_poly
					(pts
						(arc
							(start -0.2032 -0.2794)
							(mid -0.239121 -0.264521)
							(end -0.254 -0.2286)
						)
						(arc
							(start -0.254 0.2286)
							(mid -0.239121 0.264521)
							(end -0.2032 0.2794)
						)
						(arc
							(start 0.2032 0.2794)
							(mid 0.239121 0.264521)
							(end 0.254 0.2286)
						)
						(arc
							(start 0.254 -0.2286)
							(mid 0.239121 -0.264521)
							(end 0.2032 -0.2794)
						)
					)
					(width 0)
					(fill yes)
				)
			)
		)
	)
	(footprint ""
		(layer "F.Cu")
		(at 67.564 -57.658)
		(property "Reference" "R476"
			(at 0 0 0)
			(layer "F.SilkS")
			(hide yes)
			(effects
				(font
					(size 1.27 1.27)
				)
			)
		)
		(property "Value" "0R2J-2-GP"
			(at 1.7907 -1.1176 0)
			(unlocked yes)
			(layer "F.Fab")
			(hide yes)
			(effects
				(font
					(size 1.016 1.016)
					(thickness 0.1524)
				)
			)
		)
		(property "Device Type" "R402H16"
			(at 1.7907 -2.6416 0)
			(unlocked yes)
			(layer "F.Fab")
			(hide yes)
			(effects
				(font
					(size 1.016 1.016)
					(thickness 0.1524)
				)
			)
		)
		(duplicate_pad_numbers_are_jumpers no)
		(fp_rect
			(start -0.381 0.8382)
			(end 0.381 -0.8382)
			(stroke
				(width 0)
				(type default)
			)
			(fill no)
			(layer "F.CrtYd")
		)
		(fp_rect
			(start -0.381 0.8382)
			(end 0.381 -0.8382)
			(stroke
				(width 0)
				(type default)
			)
			(fill no)
			(layer "F.Fab")
		)
		(pad "1" smd custom
			(at 0 -0.4318)
			(size 0.127 0.127)
			(layers "F.Cu" "F.Mask" "F.Paste")
			(net "FPGA_SMB_HOST_DATA")
			(options
				(clearance outline)
				(anchor circle)
			)
			(primitives
				(gr_poly
					(pts
						(arc
							(start -0.2032 -0.2794)
							(mid -0.239121 -0.264521)
							(end -0.254 -0.2286)
						)
						(arc
							(start -0.254 0.2286)
							(mid -0.239121 0.264521)
							(end -0.2032 0.2794)
						)
						(arc
							(start 0.2032 0.2794)
							(mid 0.239121 0.264521)
							(end 0.254 0.2286)
						)
						(arc
							(start 0.254 -0.2286)
							(mid 0.239121 -0.264521)
							(end 0.2032 -0.2794)
						)
					)
					(width 0)
					(fill yes)
				)
			)
		)
		(pad "2" smd custom
			(at 0 0.4318)
			(size 0.127 0.127)
			(layers "F.Cu" "F.Mask" "F.Paste")
			(net "FPGA_SMB_HOST_R_DATA")
			(options
				(clearance outline)
				(anchor circle)
			)
			(primitives
				(gr_poly
					(pts
						(arc
							(start -0.2032 -0.2794)
							(mid -0.239121 -0.264521)
							(end -0.254 -0.2286)
						)
						(arc
							(start -0.254 0.2286)
							(mid -0.239121 0.264521)
							(end -0.2032 0.2794)
						)
						(arc
							(start 0.2032 0.2794)
							(mid 0.239121 0.264521)
							(end 0.254 0.2286)
						)
						(arc
							(start 0.254 -0.2286)
							(mid 0.239121 -0.264521)
							(end 0.2032 -0.2794)
						)
					)
					(width 0)
					(fill yes)
				)
			)
		)
	)
	(footprint ""
		(layer "F.Cu")
		(at 56.007 -37.592 -90)
		(property "Reference" "R98"
			(at 0 0 270)
			(layer "F.SilkS")
			(hide yes)
			(effects
				(font
					(size 1.27 1.27)
				)
			)
		)
		(property "Value" "2K2R2F-GP"
			(at 0.064008 -3.993896 270)
			(unlocked yes)
			(layer "F.Fab")
			(hide yes)
			(effects
				(font
					(size 1.016 1.016)
					(thickness 0.1524)
				)
			)
		)
		(property "Device Type" "R402H16"
			(at 0.064008 -5.517896 270)
			(unlocked yes)
			(layer "F.Fab")
			(hide yes)
			(effects
				(font
					(size 1.016 1.016)
					(thickness 0.1524)
				)
			)
		)
		(duplicate_pad_numbers_are_jumpers no)
		(fp_rect
			(start -0.381 0.8382)
			(end 0.381 -0.8382)
			(stroke
				(width 0)
				(type default)
			)
			(fill no)
			(layer "F.CrtYd")
		)
		(fp_rect
			(start -0.381 0.8382)
			(end 0.381 -0.8382)
			(stroke
				(width 0)
				(type default)
			)
			(fill no)
			(layer "F.Fab")
		)
		(pad "1" smd custom
			(at 0 -0.4318 270)
			(size 0.127 0.127)
			(layers "F.Cu" "F.Mask" "F.Paste")
			(net "P3V3_CPU")
			(options
				(clearance outline)
				(anchor circle)
			)
			(primitives
				(gr_poly
					(pts
						(arc
							(start -0.2032 -0.2794)
							(mid -0.239121 -0.264521)
							(end -0.254 -0.2286)
						)
						(arc
							(start -0.254 0.2286)
							(mid -0.239121 0.264521)
							(end -0.2032 0.2794)
						)
						(arc
							(start 0.2032 0.2794)
							(mid 0.239121 0.264521)
							(end 0.254 0.2286)
						)
						(arc
							(start 0.254 -0.2286)
							(mid 0.239121 -0.264521)
							(end 0.2032 -0.2794)
						)
					)
					(width 0)
					(fill yes)
				)
			)
		)
		(pad "2" smd custom
			(at 0 0.4318 270)
			(size 0.127 0.127)
			(layers "F.Cu" "F.Mask" "F.Paste")
			(net "SPI_CS0_N_M_1")
			(options
				(clearance outline)
				(anchor circle)
			)
			(primitives
				(gr_poly
					(pts
						(arc
							(start -0.2032 -0.2794)
							(mid -0.239121 -0.264521)
							(end -0.254 -0.2286)
						)
						(arc
							(start -0.254 0.2286)
							(mid -0.239121 0.264521)
							(end -0.2032 0.2794)
						)
						(arc
							(start 0.2032 0.2794)
							(mid 0.239121 0.264521)
							(end 0.254 0.2286)
						)
						(arc
							(start 0.254 -0.2286)
							(mid 0.239121 -0.264521)
							(end 0.2032 -0.2794)
						)
					)
					(width 0)
					(fill yes)
				)
			)
		)
	)
	(footprint ""
		(layer "F.Cu")
		(at 140.589 -52.1208 -90)
		(property "Reference" "R74"
			(at 0 0 270)
			(layer "F.SilkS")
			(hide yes)
			(effects
				(font
					(size 1.27 1.27)
				)
			)
		)
		(property "Value" "4K7R2F-GP"
			(at 1.7907 -1.1176 270)
			(unlocked yes)
			(layer "F.Fab")
			(hide yes)
			(effects
				(font
					(size 1.016 1.016)
					(thickness 0.1524)
				)
			)
		)
		(property "Device Type" "R402H16"
			(at 1.7907 -2.6416 270)
			(unlocked yes)
			(layer "F.Fab")
			(hide yes)
			(effects
				(font
					(size 1.016 1.016)
					(thickness 0.1524)
				)
			)
		)
		(duplicate_pad_numbers_are_jumpers no)
		(fp_rect
			(start -0.381 0.8382)
			(end 0.381 -0.8382)
			(stroke
				(width 0)
				(type default)
			)
			(fill no)
			(layer "F.CrtYd")
		)
		(fp_rect
			(start -0.381 0.8382)
			(end 0.381 -0.8382)
			(stroke
				(width 0)
				(type default)
			)
			(fill no)
			(layer "F.Fab")
		)
		(pad "1" smd custom
			(at 0 -0.4318 270)
			(size 0.127 0.127)
			(layers "F.Cu" "F.Mask" "F.Paste")
			(net "SPI_SW_ADDR0")
			(options
				(clearance outline)
				(anchor circle)
			)
			(primitives
				(gr_poly
					(pts
						(arc
							(start -0.2032 -0.2794)
							(mid -0.239121 -0.264521)
							(end -0.254 -0.2286)
						)
						(arc
							(start -0.254 0.2286)
							(mid -0.239121 0.264521)
							(end -0.2032 0.2794)
						)
						(arc
							(start 0.2032 0.2794)
							(mid 0.239121 0.264521)
							(end 0.254 0.2286)
						)
						(arc
							(start 0.254 -0.2286)
							(mid 0.239121 -0.264521)
							(end 0.2032 -0.2794)
						)
					)
					(width 0)
					(fill yes)
				)
			)
		)
		(pad "2" smd custom
			(at 0 0.4318 270)
			(size 0.127 0.127)
			(layers "F.Cu" "F.Mask" "F.Paste")
			(net "GND")
			(options
				(clearance outline)
				(anchor circle)
			)
			(primitives
				(gr_poly
					(pts
						(arc
							(start -0.2032 -0.2794)
							(mid -0.239121 -0.264521)
							(end -0.254 -0.2286)
						)
						(arc
							(start -0.254 0.2286)
							(mid -0.239121 0.264521)
							(end -0.2032 0.2794)
						)
						(arc
							(start 0.2032 0.2794)
							(mid 0.239121 0.264521)
							(end 0.254 0.2286)
						)
						(arc
							(start 0.254 -0.2286)
							(mid 0.239121 -0.264521)
							(end 0.2032 -0.2794)
						)
					)
					(width 0)
					(fill yes)
				)
			)
		)
	)
	(footprint ""
		(layer "F.Cu")
		(at 60.3758 -13.8176 -90)
		(property "Reference" "R481"
			(at 0 0 270)
			(layer "F.SilkS")
			(hide yes)
			(effects
				(font
					(size 1.27 1.27)
				)
			)
		)
		(property "Value" "0R2J-2-GP"
			(at 1.7907 -1.1176 270)
			(unlocked yes)
			(layer "F.Fab")
			(hide yes)
			(effects
				(font
					(size 1.016 1.016)
					(thickness 0.1524)
				)
			)
		)
		(property "Device Type" "R402H16"
			(at 1.7907 -2.6416 270)
			(unlocked yes)
			(layer "F.Fab")
			(hide yes)
			(effects
				(font
					(size 1.016 1.016)
					(thickness 0.1524)
				)
			)
		)
		(duplicate_pad_numbers_are_jumpers no)
		(fp_rect
			(start -0.381 0.8382)
			(end 0.381 -0.8382)
			(stroke
				(width 0)
				(type default)
			)
			(fill no)
			(layer "F.CrtYd")
		)
		(fp_rect
			(start -0.381 0.8382)
			(end 0.381 -0.8382)
			(stroke
				(width 0)
				(type default)
			)
			(fill no)
			(layer "F.Fab")
		)
		(pad "1" smd custom
			(at 0 -0.4318 270)
			(size 0.127 0.127)
			(layers "F.Cu" "F.Mask" "F.Paste")
			(net "CPU_RSMRST#")
			(options
				(clearance outline)
				(anchor circle)
			)
			(primitives
				(gr_poly
					(pts
						(arc
							(start -0.2032 -0.2794)
							(mid -0.239121 -0.264521)
							(end -0.254 -0.2286)
						)
						(arc
							(start -0.254 0.2286)
							(mid -0.239121 0.264521)
							(end -0.2032 0.2794)
						)
						(arc
							(start 0.2032 0.2794)
							(mid 0.239121 0.264521)
							(end 0.254 0.2286)
						)
						(arc
							(start 0.254 -0.2286)
							(mid 0.239121 -0.264521)
							(end 0.2032 -0.2794)
						)
					)
					(width 0)
					(fill yes)
				)
			)
		)
		(pad "2" smd custom
			(at 0 0.4318 270)
			(size 0.127 0.127)
			(layers "F.Cu" "F.Mask" "F.Paste")
			(net "GF_GBE_SMB_SW_EN")
			(options
				(clearance outline)
				(anchor circle)
			)
			(primitives
				(gr_poly
					(pts
						(arc
							(start -0.2032 -0.2794)
							(mid -0.239121 -0.264521)
							(end -0.254 -0.2286)
						)
						(arc
							(start -0.254 0.2286)
							(mid -0.239121 0.264521)
							(end -0.2032 0.2794)
						)
						(arc
							(start 0.2032 0.2794)
							(mid 0.239121 0.264521)
							(end 0.254 0.2286)
						)
						(arc
							(start 0.254 -0.2286)
							(mid 0.239121 -0.264521)
							(end 0.2032 -0.2794)
						)
					)
					(width 0)
					(fill yes)
				)
			)
		)
	)
)
